(kicad_pcb
	(version 20241229)
	(generator "pcbnew")
	(generator_version "9.0")
	(general
		(thickness 1.63)
		(legacy_teardrops no)
	)
	(paper "A4")
	(title_block
		(title "CM4 Baseboard")
		(date "2026-01-05")
		(rev "1.1.1")
		(company "Antmicro Ltd")
		(comment 1 "www.antmicro.com")
		(comment 9 "footprints 20-24 of 506")
	)
	(layers
		(0 "F.Cu" signal)
		(4 "In1.Cu" power)
		(6 "In2.Cu" power)
		(8 "In3.Cu" signal)
		(10 "In4.Cu" signal)
		(2 "B.Cu" signal)
		(9 "F.Adhes" user "F.Adhesive")
		(11 "B.Adhes" user "B.Adhesive")
		(13 "F.Paste" user)
		(15 "B.Paste" user)
		(5 "F.SilkS" user "F.Silkscreen")
		(7 "B.SilkS" user "B.Silkscreen")
		(1 "F.Mask" user)
		(3 "B.Mask" user)
		(17 "Dwgs.User" user "User.Drawings")
		(19 "Cmts.User" user "User.Comments")
		(21 "Eco1.User" user "User.Eco1")
		(23 "Eco2.User" user "User.Eco2")
		(25 "Edge.Cuts" user)
		(27 "Margin" user)
		(31 "F.CrtYd" user "F.Courtyard")
		(29 "B.CrtYd" user "B.Courtyard")
		(35 "F.Fab" user)
		(33 "B.Fab" user)
	)
	(footprint "antmicro-footprints:TSOT23-6"
		(layer "F.Cu")
		(at 137.317962 158.6165 -90)
		(property "Reference" "U601"
			(at 1.53 -2.17 90)
			(layer "F.SilkS")
			(effects
				(font
					(size 0.7 0.7)
					(thickness 0.15)
				)
				(justify right bottom)
			)
		)
		(property "Value" "AP22615A_TSOT26"
			(at 0 2.6 90)
			(layer "F.Fab")
			(effects
				(font
					(size 0.7 0.7)
					(thickness 0.15)
				)
				(justify right bottom)
			)
		)
		(property "Datasheet" "https://www.mouser.com/datasheet/2/115/DIOD_S_A0008958405_1-2543193.pdf"
			(at 0 0 270)
			(layer "F.Fab")
			(hide yes)
			(effects
				(font
					(size 1.27 1.27)
					(thickness 0.15)
				)
			)
		)
		(property "MPN" "AP22615AWU-7"
			(at 0 0 270)
			(unlocked yes)
			(layer "F.Fab")
			(hide yes)
			(effects
				(font
					(size 1 1)
					(thickness 0.15)
				)
			)
		)
		(property "Manufacturer" "Diodes Incorporated"
			(at 0 0 270)
			(unlocked yes)
			(layer "F.Fab")
			(hide yes)
			(effects
				(font
					(size 1 1)
					(thickness 0.15)
				)
			)
		)
		(property "Author" "Antmicro"
			(at 0 0 270)
			(unlocked yes)
			(layer "F.Fab")
			(hide yes)
			(effects
				(font
					(size 1 1)
					(thickness 0.15)
				)
			)
		)
		(property "License" "Apache-2.0"
			(at 0 0 270)
			(unlocked yes)
			(layer "F.Fab")
			(hide yes)
			(effects
				(font
					(size 1 1)
					(thickness 0.15)
				)
			)
		)
		(sheetname "/CSI/")
		(sheetfile "csi.kicad_sch")
		(attr smd)
		(fp_line
			(start -1 1.55)
			(end -1 1.4)
			(stroke
				(width 0.15)
				(type solid)
			)
			(layer "F.SilkS")
		)
		(fp_line
			(start 1 1.55)
			(end -1 1.55)
			(stroke
				(width 0.15)
				(type solid)
			)
			(layer "F.SilkS")
		)
		(fp_line
			(start 1 1.55)
			(end 1 1.4)
			(stroke
				(width 0.15)
				(type solid)
			)
			(layer "F.SilkS")
		)
		(fp_line
			(start 1 -1.497)
			(end 1 -1.375)
			(stroke
				(width 0.15)
				(type solid)
			)
			(layer "F.SilkS")
		)
		(fp_line
			(start 1 -1.497)
			(end -1 -1.5)
			(stroke
				(width 0.15)
				(type solid)
			)
			(layer "F.SilkS")
		)
		(fp_line
			(start -1 -1.5)
			(end -1 -1.375)
			(stroke
				(width 0.15)
				(type solid)
			)
			(layer "F.SilkS")
		)
		(fp_circle
			(center -1.44 -1.5)
			(end -1.39 -1.5)
			(stroke
				(width 0.15)
				(type solid)
			)
			(fill yes)
			(layer "F.SilkS")
		)
		(fp_rect
			(start 1.93 -1.7)
			(end -1.93 1.7)
			(stroke
				(width 0.05)
				(type solid)
			)
			(fill no)
			(layer "F.CrtYd")
		)
		(fp_line
			(start -0.45 -1.521)
			(end -0.876 -1.096)
			(stroke
				(width 0.15)
				(type solid)
			)
			(layer "F.Fab")
		)
		(fp_rect
			(start 0.875 1.528)
			(end -0.875 -1.525)
			(stroke
				(width 0.15)
				(type solid)
			)
			(fill no)
			(layer "F.Fab")
		)
		(fp_text user "${REFERENCE}"
			(at -1.93 3.8 270)
			(layer "F.Fab")
			(effects
				(font
					(size 0.7 0.7)
					(thickness 0.15)
				)
				(justify left bottom)
			)
		)
		(fp_text user "Author: Antmicro"
			(at -1.93 5 270)
			(layer "F.Fab")
			(effects
				(font
					(size 0.7 0.7)
					(thickness 0.15)
				)
				(justify left bottom)
			)
		)
		(fp_text user "License: Apache-2.0"
			(at -1.93 6.199 270)
			(layer "F.Fab")
			(effects
				(font
					(size 0.7 0.7)
					(thickness 0.15)
				)
				(justify left bottom)
			)
		)
		(pad "1" smd rect
			(at -1.301 -0.947 180)
			(size 0.7 1.2)
			(layers "F.Cu" "F.Mask" "F.Paste")
			(net 20 "/CSI/CSI_5V")
			(pinfunction "OUT")
			(pintype "power_out")
		)
		(pad "2" smd rect
			(at -1.301 0.004 180)
			(size 0.7 1.2)
			(layers "F.Cu" "F.Mask" "F.Paste")
			(net 3 "GND")
			(pinfunction "GND")
			(pintype "power_in")
		)
		(pad "3" smd rect
			(at -1.301 0.954 180)
			(size 0.7 1.2)
			(layers "F.Cu" "F.Mask" "F.Paste")
			(net 370 "Net-(U601-FLG)")
			(pinfunction "FLG")
			(pintype "output")
		)
		(pad "4" smd rect
			(at 1.299 0.954 180)
			(size 0.7 1.2)
			(layers "F.Cu" "F.Mask" "F.Paste")
			(net 369 "/CSI/CamCtrl.EN")
			(pinfunction "EN")
			(pintype "input")
		)
		(pad "5" smd rect
			(at 1.299 0.004 180)
			(size 0.7 1.2)
			(layers "F.Cu" "F.Mask" "F.Paste")
			(net 372 "Net-(U601-ISET)")
			(pinfunction "ISET")
			(pintype "passive")
		)
		(pad "6" smd rect
			(at 1.299 -0.947 180)
			(size 0.7 1.2)
			(layers "F.Cu" "F.Mask" "F.Paste")
			(net 10 "+5V")
			(pinfunction "IN")
			(pintype "power_in")
		)
	)
	(footprint "antmicro-footprints:R_0402_1005Metric"
		(layer "F.Cu")
		(at 66.342962 143.9165 180)
		(descr "Resistor SMD 0402")
		(tags "resistor SMD 0402")
		(property "Reference" "R1"
			(at -0.425 0.55 0)
			(layer "F.SilkS")
			(effects
				(font
					(size 0.7 0.7)
					(thickness 0.15)
				)
				(justify right bottom)
			)
		)
		(property "Value" "R_100k_0402"
			(at -1.011843 1.772047 0)
			(layer "F.Fab")
			(effects
				(font
					(size 0.7 0.7)
					(thickness 0.15)
				)
				(justify right bottom)
			)
		)
		(property "Datasheet" "https://www.bourns.com/docs/product-datasheets/cr.pdf"
			(at 0 0 180)
			(layer "F.Fab")
			(hide yes)
			(effects
				(font
					(size 1.27 1.27)
					(thickness 0.15)
				)
			)
		)
		(property "Manufacturer" "Bourns"
			(at 0 0 180)
			(unlocked yes)
			(layer "F.Fab")
			(hide yes)
			(effects
				(font
					(size 1 1)
					(thickness 0.15)
				)
			)
		)
		(property "MPN" "CR0402-FX-1003GLF"
			(at 0 0 180)
			(unlocked yes)
			(layer "F.Fab")
			(hide yes)
			(effects
				(font
					(size 1 1)
					(thickness 0.15)
				)
			)
		)
		(property "Val" "100k"
			(at 0 0 180)
			(unlocked yes)
			(layer "F.Fab")
			(hide yes)
			(effects
				(font
					(size 1 1)
					(thickness 0.15)
				)
			)
		)
		(property "License" "Apache-2.0"
			(at 0 0 180)
			(unlocked yes)
			(layer "F.Fab")
			(hide yes)
			(effects
				(font
					(size 1 1)
					(thickness 0.15)
				)
			)
		)
		(property "Author" "Antmicro"
			(at 0 0 180)
			(unlocked yes)
			(layer "F.Fab")
			(hide yes)
			(effects
				(font
					(size 1 1)
					(thickness 0.15)
				)
			)
		)
		(property "Tolerance" "1%"
			(at 0 0 180)
			(unlocked yes)
			(layer "F.Fab")
			(hide yes)
			(effects
				(font
					(size 1 1)
					(thickness 0.15)
				)
			)
		)
		(sheetname "/Compute module/")
		(sheetfile "compute-module.kicad_sch")
		(attr smd)
		(fp_rect
			(start -0.925 -0.47)
			(end 0.925 0.47)
			(stroke
				(width 0.05)
				(type default)
			)
			(fill no)
			(layer "F.CrtYd")
		)
		(fp_rect
			(start -0.5 -0.25)
			(end 0.5 0.25)
			(stroke
				(width 0.15)
				(type solid)
			)
			(fill no)
			(layer "F.Fab")
		)
		(fp_text user "${REFERENCE}"
			(at -0.95 3.168 180)
			(layer "F.Fab")
			(effects
				(font
					(size 0.7 0.7)
					(thickness 0.15)
				)
				(justify left bottom)
			)
		)
		(fp_text user "License: Apache-2.0"
			(at -0.95 5.169 180)
			(layer "F.Fab")
			(effects
				(font
					(size 0.7 0.7)
					(thickness 0.15)
				)
				(justify left bottom)
			)
		)
		(fp_text user "Author: Antmicro"
			(at -0.95 4.169 180)
			(layer "F.Fab")
			(effects
				(font
					(size 0.7 0.7)
					(thickness 0.15)
				)
				(justify left bottom)
			)
		)
		(pad "1" smd roundrect
			(at -0.48 0 180)
			(size 0.59 0.64)
			(layers "F.Cu" "F.Mask" "F.Paste")
			(roundrect_rratio 0.25)
			(net 491 "Net-(Q206-G)")
			(pintype "passive")
		)
		(pad "2" smd roundrect
			(at 0.48 0 180)
			(size 0.59 0.64)
			(layers "F.Cu" "F.Mask" "F.Paste")
			(roundrect_rratio 0.25)
			(net 9 "+3V3")
			(pintype "passive")
		)
	)
	(footprint "antmicro-footprints:LED_0603_1608Metric_G"
		(layer "F.Cu")
		(at 132.187962 156.0165 180)
		(descr "LED SMD 0603 Green")
		(tags "LED SMD 0603 Green")
		(property "Reference" "D602"
			(at -0.38 1.05 0)
			(layer "F.SilkS")
			(effects
				(font
					(size 0.7 0.7)
					(thickness 0.15)
				)
				(justify right bottom)
			)
		)
		(property "Value" "LED_G_0603_KP-1608CGCK"
			(at -0.001 1.599 0)
			(layer "F.Fab")
			(effects
				(font
					(size 0.7 0.7)
					(thickness 0.15)
				)
				(justify right bottom)
			)
		)
		(property "Datasheet" "http://www.kingbright.com/attachments/file/psearch//000/00/00/KP-1608CGCK(Ver.23B).pdf"
			(at 0 0 180)
			(layer "F.Fab")
			(hide yes)
			(effects
				(font
					(size 1.27 1.27)
					(thickness 0.15)
				)
			)
		)
		(property "MPN" "KP-1608CGCK"
			(at 0 0 180)
			(unlocked yes)
			(layer "F.Fab")
			(hide yes)
			(effects
				(font
					(size 1 1)
					(thickness 0.15)
				)
			)
		)
		(property "Manufacturer" "Kingbright"
			(at 0 0 180)
			(unlocked yes)
			(layer "F.Fab")
			(hide yes)
			(effects
				(font
					(size 1 1)
					(thickness 0.15)
				)
			)
		)
		(property "Color" "Green"
			(at 0 0 180)
			(unlocked yes)
			(layer "F.Fab")
			(hide yes)
			(effects
				(font
					(size 1 1)
					(thickness 0.15)
				)
			)
		)
		(property "Author" "Antmicro"
			(at 0 0 180)
			(unlocked yes)
			(layer "F.Fab")
			(hide yes)
			(effects
				(font
					(size 1 1)
					(thickness 0.15)
				)
			)
		)
		(property "License" "Apache-2.0"
			(at 0 0 180)
			(unlocked yes)
			(layer "F.Fab")
			(hide yes)
			(effects
				(font
					(size 1 1)
					(thickness 0.15)
				)
			)
		)
		(sheetname "/CSI/")
		(sheetfile "csi.kicad_sch")
		(attr smd)
		(fp_line
			(start 0.22 0.35)
			(end -0.22 0.35)
			(stroke
				(width 0.15)
				(type solid)
			)
			(layer "F.SilkS")
		)
		(fp_line
			(start 0.22 -0.35)
			(end -0.22 -0.35)
			(stroke
				(width 0.15)
				(type solid)
			)
			(layer "F.SilkS")
		)
		(fp_line
			(start 0.105328 0.201008)
			(end 0.105328 -0.198992)
			(stroke
				(width 0.1)
				(type solid)
			)
			(layer "F.SilkS")
		)
		(fp_line
			(start 0.105328 0.201008)
			(end -0.094672 0.001008)
			(stroke
				(width 0.1)
				(type solid)
			)
			(layer "F.SilkS")
		)
		(fp_line
			(start 0.105328 0.001008)
			(end 0.24 0.001)
			(stroke
				(width 0.1)
				(type solid)
			)
			(layer "F.SilkS")
		)
		(fp_line
			(start -0.094672 0.201008)
			(end -0.094672 -0.198992)
			(stroke
				(width 0.1)
				(type solid)
			)
			(layer "F.SilkS")
		)
		(fp_line
			(start -0.094672 0.001008)
			(end 0.105328 -0.198992)
			(stroke
				(width 0.1)
				(type solid)
			)
			(layer "F.SilkS")
		)
		(fp_line
			(start -0.094672 0.001008)
			(end -0.24 0.001008)
			(stroke
				(width 0.1)
				(type solid)
			)
			(layer "F.SilkS")
		)
		(fp_line
			(start -1.18 -0.319)
			(end -1.18 0.321)
			(stroke
				(width 0.15)
				(type solid)
			)
			(layer "F.SilkS")
		)
		(fp_rect
			(start 1.25 0.65)
			(end -1.25 -0.65)
			(stroke
				(width 0.05)
				(type solid)
			)
			(fill no)
			(layer "F.CrtYd")
		)
		(fp_line
			(start 0.599 0)
			(end 0.201 0)
			(stroke
				(width 0.15)
				(type solid)
			)
			(layer "F.Fab")
		)
		(fp_line
			(start 0.201 0.2)
			(end 0.201 0)
			(stroke
				(width 0.15)
				(type solid)
			)
			(layer "F.Fab")
		)
		(fp_line
			(start 0.201 0)
			(end 0.201 -0.202)
			(stroke
				(width 0.15)
				(type solid)
			)
			(layer "F.Fab")
		)
		(fp_line
			(start 0.201 -0.202)
			(end -0.101 0)
			(stroke
				(width 0.15)
				(type solid)
			)
			(layer "F.Fab")
		)
		(fp_line
			(start -0.101 0)
			(end 0.201 0.2)
			(stroke
				(width 0.15)
				(type solid)
			)
			(layer "F.Fab")
		)
		(fp_line
			(start -0.199 0.2)
			(end -0.199 0.1)
			(stroke
				(width 0.15)
				(type solid)
			)
			(layer "F.Fab")
		)
		(fp_line
			(start -0.199 0)
			(end -0.597 0)
			(stroke
				(width 0.15)
				(type solid)
			)
			(layer "F.Fab")
		)
		(fp_line
			(start -0.199 -0.202)
			(end -0.199 0.1)
			(stroke
				(width 0.15)
				(type solid)
			)
			(layer "F.Fab")
		)
		(fp_rect
			(start 0.848 0.4)
			(end -0.85 -0.402)
			(stroke
				(width 0.15)
				(type solid)
			)
			(fill no)
			(layer "F.Fab")
		)
		(fp_text user "Author: Antmicro"
			(at -1.4224 4.799 180)
			(layer "F.Fab")
			(effects
				(font
					(size 0.7 0.7)
					(thickness 0.15)
				)
				(justify left bottom)
			)
		)
		(fp_text user "License: Apache-2.0"
			(at -1.4224 3.599 180)
			(layer "F.Fab")
			(effects
				(font
					(size 0.7 0.7)
					(thickness 0.15)
				)
				(justify left bottom)
			)
		)
		(fp_text user "${REFERENCE}"
			(at -1.4224 5.999 180)
			(layer "F.Fab")
			(effects
				(font
					(size 0.7 0.7)
					(thickness 0.15)
				)
				(justify left bottom)
			)
		)
		(pad "1" smd roundrect
			(at -0.7 0)
			(size 0.8 1)
			(layers "F.Cu" "F.Mask" "F.Paste")
			(roundrect_rratio 0.2)
			(net 3 "GND")
			(pinfunction "C")
			(pintype "passive")
		)
		(pad "2" smd roundrect
			(at 0.7 0)
			(size 0.8 1)
			(layers "F.Cu" "F.Mask" "F.Paste")
			(roundrect_rratio 0.2)
			(net 480 "Net-(D602-A)")
			(pinfunction "A")
			(pintype "passive")
		)
	)
	(footprint "antmicro-footprints:TP_SMD_0.75mm"
		(layer "F.Cu")
		(at 118.142962 125.25 180)
		(property "Reference" "TP502"
			(at -3.85 -0.5 0)
			(layer "F.SilkS")
			(effects
				(font
					(size 0.7 0.7)
					(thickness 0.15)
				)
				(justify right bottom)
			)
		)
		(property "Value" "TP_0.75mm_SMD"
			(at 0 1.2 0)
			(layer "F.Fab")
			(effects
				(font
					(size 0.7 0.7)
					(thickness 0.15)
				)
				(justify right bottom)
			)
		)
		(property "MPN" ""
			(at 0 0 180)
			(unlocked yes)
			(layer "F.Fab")
			(hide yes)
			(effects
				(font
					(size 1 1)
					(thickness 0.15)
				)
			)
		)
		(property "Manufacturer" ""
			(at 0 0 180)
			(unlocked yes)
			(layer "F.Fab")
			(hide yes)
			(effects
				(font
					(size 1 1)
					(thickness 0.15)
				)
			)
		)
		(property "Author" "Antmicro"
			(at 0 0 180)
			(unlocked yes)
			(layer "F.Fab")
			(hide yes)
			(effects
				(font
					(size 1 1)
					(thickness 0.15)
				)
			)
		)
		(property "License" "Apache-2.0"
			(at 0 0 180)
			(unlocked yes)
			(layer "F.Fab")
			(hide yes)
			(effects
				(font
					(size 1 1)
					(thickness 0.15)
				)
			)
		)
		(sheetname "/NVMe & microSD/")
		(sheetfile "nvme-micro-sd.kicad_sch")
		(attr exclude_from_pos_files exclude_from_bom)
		(fp_circle
			(center 0 0)
			(end 0.475 0)
			(stroke
				(width 0.05)
				(type default)
			)
			(fill no)
			(layer "F.CrtYd")
		)
		(fp_text user "License: Apache-2.0"
			(at -0.4 5.101 180)
			(layer "F.Fab")
			(effects
				(font
					(size 0.7 0.7)
					(thickness 0.15)
				)
				(justify left bottom)
			)
		)
		(fp_text user "Author: Antmicro"
			(at -0.4 3.901 180)
			(layer "F.Fab")
			(effects
				(font
					(size 0.7 0.7)
					(thickness 0.15)
				)
				(justify left bottom)
			)
		)
		(fp_text user "${REFERENCE}"
			(at -0.4 2.7 180)
			(layer "F.Fab")
			(effects
				(font
					(size 0.7 0.7)
					(thickness 0.15)
				)
				(justify left bottom)
			)
		)
		(pad "1" smd circle
			(at 0 0 180)
			(size 0.75 0.75)
			(layers "F.Cu" "F.Mask")
			(net 185 "Net-(J501-ALERT)")
			(pinfunction "1")
			(pintype "passive")
		)
	)
	(footprint "antmicro-footprints:C_0402_1005Metric"
		(layer "F.Cu")
		(at 89.667962 132.442236 180)
		(descr "Capacitor SMD 0402")
		(tags "capacitor SMD 0402")
		(property "Reference" "C920"
			(at -1.39 4.060736 0)
			(layer "F.SilkS")
			(effects
				(font
					(size 0.7 0.7)
					(thickness 0.15)
				)
				(justify right bottom)
			)
		)
		(property "Value" "C_100n_0402"
			(at -1.022927 2.155213 0)
			(layer "F.Fab")
			(effects
				(font
					(size 0.7 0.7)
					(thickness 0.15)
				)
				(justify right bottom)
			)
		)
		(property "Datasheet" "https://www.murata.com/products/productdetail?partno=GRM155R61H104KE14%23"
			(at 0 0 180)
			(layer "F.Fab")
			(hide yes)
			(effects
				(font
					(size 1.27 1.27)
					(thickness 0.15)
				)
			)
		)
		(property "Manufacturer" "Murata"
			(at 0 0 180)
			(unlocked yes)
			(layer "F.Fab")
			(hide yes)
			(effects
				(font
					(size 1 1)
					(thickness 0.15)
				)
			)
		)
		(property "MPN" "GRM155R61H104KE14D"
			(at 0 0 180)
			(unlocked yes)
			(layer "F.Fab")
			(hide yes)
			(effects
				(font
					(size 1 1)
					(thickness 0.15)
				)
			)
		)
		(property "Val" "100n"
			(at 0 0 180)
			(unlocked yes)
			(layer "F.Fab")
			(hide yes)
			(effects
				(font
					(size 1 1)
					(thickness 0.15)
				)
			)
		)
		(property "License" "Apache-2.0"
			(at 0 0 180)
			(unlocked yes)
			(layer "F.Fab")
			(hide yes)
			(effects
				(font
					(size 1 1)
					(thickness 0.15)
				)
			)
		)
		(property "Author" "Antmicro"
			(at 0 0 180)
			(unlocked yes)
			(layer "F.Fab")
			(hide yes)
			(effects
				(font
					(size 1 1)
					(thickness 0.15)
				)
			)
		)
		(property "Voltage" "50V"
			(at 0 0 180)
			(unlocked yes)
			(layer "F.Fab")
			(hide yes)
			(effects
				(font
					(size 1 1)
					(thickness 0.15)
				)
			)
		)
		(property "Dielectric" "X5R"
			(at 0 0 180)
			(unlocked yes)
			(layer "F.Fab")
			(hide yes)
			(effects
				(font
					(size 1 1)
					(thickness 0.15)
				)
			)
		)
		(sheetname "/USB/")
		(sheetfile "usb.kicad_sch")
		(attr smd)
		(fp_rect
			(start -0.925 -0.47)
			(end 0.925 0.47)
			(stroke
				(width 0.05)
				(type default)
			)
			(fill no)
			(layer "F.CrtYd")
		)
		(fp_line
			(start 0.504 0.248)
			(end -0.494 0.248)
			(stroke
				(width 0.15)
				(type solid)
			)
			(layer "F.Fab")
		)
		(fp_line
			(start 0.504 -0.25)
			(end 0.504 0.248)
			(stroke
				(width 0.15)
				(type solid)
			)
			(layer "F.Fab")
		)
		(fp_line
			(start -0.494 0.248)
			(end -0.494 -0.25)
			(stroke
				(width 0.15)
				(type solid)
			)
			(layer "F.Fab")
		)
		(fp_line
			(start -0.494 -0.25)
			(end 0.504 -0.25)
			(stroke
				(width 0.15)
				(type solid)
			)
			(layer "F.Fab")
		)
		(fp_text user "${REFERENCE}"
			(at -0.939 4.599 180)
			(layer "F.Fab")
			(effects
				(font
					(size 0.7 0.7)
					(thickness 0.15)
				)
				(justify left bottom)
			)
		)
		(fp_text user "Author: Antmicro"
			(at -0.939 3.399 180)
			(layer "F.Fab")
			(effects
				(font
					(size 0.7 0.7)
					(thickness 0.15)
				)
				(justify left bottom)
			)
		)
		(fp_text user "License: Apache-2.0"
			(at -0.939 5.799 180)
			(layer "F.Fab")
			(effects
				(font
					(size 0.7 0.7)
					(thickness 0.15)
				)
				(justify left bottom)
			)
		)
		(pad "1" smd roundrect
			(at -0.48 0 180)
			(size 0.59 0.64)
			(layers "F.Cu" "F.Mask" "F.Paste")
			(roundrect_rratio 0.25)
			(net 211 "/USB/VCC_PD")
			(pintype "passive")
		)
		(pad "2" smd roundrect
			(at 0.48 0 180)
			(size 0.59 0.64)
			(layers "F.Cu" "F.Mask" "F.Paste")
			(roundrect_rratio 0.25)
			(net 3 "GND")
			(pintype "passive")
		)
	)
)
